# S9S_MB_2U (Grand Teton) — schematic netlist excerpt (pin names and nets, part order shuffled) for the footprints in the layout excerpt that follows; sources: Cadence DE-HDL packaged netlist, KiCad conversion of 03242023_DA0F0TMBIJ0_F0T_Motherboard_J_brd_V01_OCP.brd

R3094  Q_RES  130 1% CHIP  pkg 0402LF  page 254 : A = LED_PWRGD_PVPP_HBM_CPU1 ; B = P3V3_AUX
PC1265  Q_CAP  0.22UF 25V 10% X7R  pkg C0402  page 299 : A = SW_PVPP_HBM_CPU1_BST ; B = SW_PVPP_HBM_CPU1_SW

(kicad_pcb
	(version 20260206)
	(generator "pcbnew")
	(generator_version "10.0")
	(general
		(thickness 1.6)
		(legacy_teardrops no)
	)
	(paper "A4")
	(title_block
		(title "03242023_DA0F0TMBIJ0_F0T_Motherboard_J_brd_V01_OCP.brd")
		(comment 1 "Grand Teton / footprints 562-563 of 6105")
	)
	(layers
		(0 "F.Cu" signal "TOP")
		(4 "In1.Cu" signal "GND")
		(6 "In2.Cu" signal "IN1")
		(8 "In3.Cu" signal "GND1")
		(10 "In4.Cu" signal "IN2")
		(12 "In5.Cu" signal "GND2")
		(14 "In6.Cu" signal "IN3")
		(16 "In7.Cu" signal "GND3")
		(18 "In8.Cu" signal "VCC")
		(20 "In9.Cu" signal "VCC1")
		(22 "In10.Cu" signal "GND4")
		(24 "In11.Cu" signal "IN4")
		(26 "In12.Cu" signal "GND5")
		(28 "In13.Cu" signal "IN5")
		(30 "In14.Cu" signal "GND6")
		(32 "In15.Cu" signal "IN6")
		(34 "In16.Cu" signal "GND7")
		(2 "B.Cu" signal "BOTTOM")
		(9 "F.Adhes" user "F.Adhesive")
		(11 "B.Adhes" user "B.Adhesive")
		(13 "F.Paste" user "Package Geometry/Pastemask Top")
		(15 "B.Paste" user "Package Geometry/Pastemask Bottom")
		(5 "F.SilkS" user "Ref Des/Silkscreen Top")
		(7 "B.SilkS" user "Ref Des/Silkscreen Bottom")
		(1 "F.Mask" user "Board Geometry/Soldermask Top")
		(3 "B.Mask" user "Board Geometry/Soldermask Bottom")
		(17 "Dwgs.User" user "User.Drawings")
		(19 "Cmts.User" user "User.Comments")
		(21 "Eco1.User" user "User.Eco1")
		(23 "Eco2.User" user "User.Eco2")
		(25 "Edge.Cuts" user "Board Geometry/Outline")
		(27 "Margin" user)
		(31 "F.CrtYd" user "Package Geometry/Place Bound Top")
		(29 "B.CrtYd" user "Package Geometry/Place Bound Bottom")
		(35 "F.Fab" user "Ref Des/Assembly Top")
		(33 "B.Fab" user "Ref Des/Assembly Bottom")
	)
	(footprint ""
		(layer "F.Cu")
		(at 123.370848 -361.563158 90)
		(property "Reference" "PC1265"
			(at 0 0 90)
			(layer "F.SilkS")
			(hide yes)
			(effects
				(font
					(size 1.27 1.27)
				)
			)
		)
		(property "Value" ""
			(at 0 0 90)
			(layer "F.Fab")
			(effects
				(font
					(size 1.27 1.27)
				)
			)
		)
		(duplicate_pad_numbers_are_jumpers no)
		(fp_line
			(start 0.7874 -0.4064)
			(end 0.7874 0.4064)
			(stroke
				(width 0.1524)
				(type default)
			)
			(layer "F.SilkS")
		)
		(fp_line
			(start -0.7874 -0.4064)
			(end 0.7874 -0.4064)
			(stroke
				(width 0.1524)
				(type default)
			)
			(layer "F.SilkS")
		)
		(fp_line
			(start 0.7874 0.4064)
			(end -0.7874 0.4064)
			(stroke
				(width 0.1524)
				(type default)
			)
			(layer "F.SilkS")
		)
		(fp_line
			(start -0.7874 0.4064)
			(end -0.7874 -0.4064)
			(stroke
				(width 0.1524)
				(type default)
			)
			(layer "F.SilkS")
		)
		(fp_line
			(start -0.12065 -0.305054)
			(end -0.12065 -0.2794)
			(stroke
				(width 0.1)
				(type default)
			)
			(layer "F.Fab")
		)
		(fp_line
			(start -0.67945 -0.305054)
			(end -0.12065 -0.305054)
			(stroke
				(width 0.1)
				(type default)
			)
			(layer "F.Fab")
		)
		(fp_line
			(start 0.67945 -0.3048)
			(end 0.67945 0.3048)
			(stroke
				(width 0.1)
				(type default)
			)
			(layer "F.Fab")
		)
		(fp_line
			(start 0.12065 -0.3048)
			(end 0.67945 -0.3048)
			(stroke
				(width 0.1)
				(type default)
			)
			(layer "F.Fab")
		)
		(fp_line
			(start 0.12065 -0.2794)
			(end 0.12065 -0.3048)
			(stroke
				(width 0.1)
				(type default)
			)
			(layer "F.Fab")
		)
		(fp_line
			(start -0.12065 -0.2794)
			(end 0.12065 -0.2794)
			(stroke
				(width 0.1)
				(type default)
			)
			(layer "F.Fab")
		)
		(fp_line
			(start 0.120396 0.2794)
			(end -0.12065 0.2794)
			(stroke
				(width 0.1)
				(type default)
			)
			(layer "F.Fab")
		)
		(fp_line
			(start -0.12065 0.2794)
			(end -0.12065 0.3048)
			(stroke
				(width 0.1)
				(type default)
			)
			(layer "F.Fab")
		)
		(fp_line
			(start 0.67945 0.3048)
			(end 0.120396 0.3048)
			(stroke
				(width 0.1)
				(type default)
			)
			(layer "F.Fab")
		)
		(fp_line
			(start 0.120396 0.3048)
			(end 0.120396 0.2794)
			(stroke
				(width 0.1)
				(type default)
			)
			(layer "F.Fab")
		)
		(fp_line
			(start -0.12065 0.3048)
			(end -0.67945 0.3048)
			(stroke
				(width 0.1)
				(type default)
			)
			(layer "F.Fab")
		)
		(fp_line
			(start -0.67945 0.3048)
			(end -0.67945 -0.305054)
			(stroke
				(width 0.1)
				(type default)
			)
			(layer "F.Fab")
		)
		(pad "1" smd circle
			(at -0.40005 0 90)
			(size 0 0)
			(layers "F.Cu" "F.Mask" "F.Paste")
			(net "SW_PVPP_HBM_CPU1_BST")
		)
		(pad "2" smd circle
			(at 0.40005 0 90)
			(size 0 0)
			(layers "F.Cu" "F.Mask" "F.Paste")
			(net "SW_PVPP_HBM_CPU1_SW")
		)
	)
	(footprint ""
		(layer "F.Cu")
		(at 76.90231 -74.901552 -90)
		(property "Reference" "R3094"
			(at 0 0 270)
			(layer "F.SilkS")
			(hide yes)
			(effects
				(font
					(size 1.27 1.27)
				)
			)
		)
		(property "Value" ""
			(at 0 0 270)
			(layer "F.Fab")
			(effects
				(font
					(size 1.27 1.27)
				)
			)
		)
		(duplicate_pad_numbers_are_jumpers no)
		(fp_line
			(start -0.7874 0.4064)
			(end -0.7874 -0.4064)
			(stroke
				(width 0.1524)
				(type default)
			)
			(layer "F.SilkS")
		)
		(fp_line
			(start 0.7874 0.4064)
			(end -0.7874 0.4064)
			(stroke
				(width 0.1524)
				(type default)
			)
			(layer "F.SilkS")
		)
		(fp_line
			(start -0.7874 -0.4064)
			(end 0.7874 -0.4064)
			(stroke
				(width 0.1524)
				(type default)
			)
			(layer "F.SilkS")
		)
		(fp_line
			(start 0.7874 -0.4064)
			(end 0.7874 0.4064)
			(stroke
				(width 0.1524)
				(type default)
			)
			(layer "F.SilkS")
		)
		(fp_line
			(start -0.67945 0.3048)
			(end -0.67945 -0.305054)
			(stroke
				(width 0.1)
				(type default)
			)
			(layer "F.Fab")
		)
		(fp_line
			(start -0.12065 0.3048)
			(end -0.67945 0.3048)
			(stroke
				(width 0.1)
				(type default)
			)
			(layer "F.Fab")
		)
		(fp_line
			(start 0.120396 0.3048)
			(end 0.120396 0.2794)
			(stroke
				(width 0.1)
				(type default)
			)
			(layer "F.Fab")
		)
		(fp_line
			(start 0.67945 0.3048)
			(end 0.120396 0.3048)
			(stroke
				(width 0.1)
				(type default)
			)
			(layer "F.Fab")
		)
		(fp_line
			(start -0.12065 0.2794)
			(end -0.12065 0.3048)
			(stroke
				(width 0.1)
				(type default)
			)
			(layer "F.Fab")
		)
		(fp_line
			(start 0.120396 0.2794)
			(end -0.12065 0.2794)
			(stroke
				(width 0.1)
				(type default)
			)
			(layer "F.Fab")
		)
		(fp_line
			(start -0.12065 -0.2794)
			(end 0.12065 -0.2794)
			(stroke
				(width 0.1)
				(type default)
			)
			(layer "F.Fab")
		)
		(fp_line
			(start 0.12065 -0.2794)
			(end 0.12065 -0.3048)
			(stroke
				(width 0.1)
				(type default)
			)
			(layer "F.Fab")
		)
		(fp_line
			(start 0.12065 -0.3048)
			(end 0.67945 -0.3048)
			(stroke
				(width 0.1)
				(type default)
			)
			(layer "F.Fab")
		)
		(fp_line
			(start 0.67945 -0.3048)
			(end 0.67945 0.3048)
			(stroke
				(width 0.1)
				(type default)
			)
			(layer "F.Fab")
		)
		(fp_line
			(start -0.67945 -0.305054)
			(end -0.12065 -0.305054)
			(stroke
				(width 0.1)
				(type default)
			)
			(layer "F.Fab")
		)
		(fp_line
			(start -0.12065 -0.305054)
			(end -0.12065 -0.2794)
			(stroke
				(width 0.1)
				(type default)
			)
			(layer "F.Fab")
		)
		(pad "1" smd circle
			(at -0.40005 0 270)
			(size 0 0)
			(layers "F.Cu" "F.Mask" "F.Paste")
			(net "LED_PWRGD_PVPP_HBM_CPU1")
		)
		(pad "2" smd circle
			(at 0.40005 0 270)
			(size 0 0)
			(layers "F.Cu" "F.Mask" "F.Paste")
			(net "P3V3_AUX")
		)
	)
)
